(kicad_pcb
	(version 20260206)
	(generator "pcbnew")
	(generator_version "10.0")
	(general
		(thickness 1.6)
		(legacy_teardrops no)
	)
	(paper "A4")
	(title_block
		(title "Wiwynn_Tioga_Pass_MB.brd")
		(comment 1 "Tioga Pass / footprints 351-357 of 4770")
	)
	(layers
		(0 "F.Cu" signal "TOP")
		(4 "In1.Cu" signal "L2GND")
		(6 "In2.Cu" signal "L3")
		(8 "In3.Cu" signal "L4GND")
		(10 "In4.Cu" signal "L5")
		(12 "In5.Cu" signal "L6GND")
		(14 "In6.Cu" signal "L7VCC")
		(16 "In7.Cu" signal "L8VCC")
		(18 "In8.Cu" signal "L9GND")
		(20 "In9.Cu" signal "L10")
		(22 "In10.Cu" signal "L11GND")
		(24 "In11.Cu" signal "L12")
		(26 "In12.Cu" signal "L13GND")
		(2 "B.Cu" signal "BOTTOM")
		(9 "F.Adhes" user "F.Adhesive")
		(11 "B.Adhes" user "B.Adhesive")
		(13 "F.Paste" user "Package Geometry/Pastemask Top")
		(15 "B.Paste" user "Package Geometry/Pastemask Bottom")
		(5 "F.SilkS" user "Ref Des/Silkscreen Top")
		(7 "B.SilkS" user "Ref Des/Silkscreen Bottom")
		(1 "F.Mask" user "Board Geometry/Soldermask Top")
		(3 "B.Mask" user "Board Geometry/Soldermask Bottom")
		(17 "Dwgs.User" user "User.Drawings")
		(19 "Cmts.User" user "User.Comments")
		(21 "Eco1.User" user "User.Eco1")
		(23 "Eco2.User" user "User.Eco2")
		(25 "Edge.Cuts" user "Board Geometry/Outline")
		(27 "Margin" user)
		(31 "F.CrtYd" user "Package Geometry/Place Bound Top")
		(29 "B.CrtYd" user "Package Geometry/Place Bound Bottom")
		(35 "F.Fab" user "Ref Des/Assembly Top")
		(33 "B.Fab" user "Ref Des/Assembly Bottom")
	)
	(footprint ""
		(layer "F.Cu")
		(at 422.2877 -105.029 -90)
		(property "Reference" "R9W18"
			(at -0.8382 -0.67818 270)
			(unlocked yes)
			(layer "F.SilkS")
			(effects
				(font
					(size 0.4064 0.254)
					(thickness 0.1524)
				)
				(justify left)
			)
		)
		(property "Value" ""
			(at 0 0 270)
			(layer "F.Fab")
			(effects
				(font
					(size 1.27 1.27)
				)
			)
		)
		(duplicate_pad_numbers_are_jumpers no)
		(fp_poly
			(pts
				(xy -0.2794 -0.1016) (xy 0.2794 -0.1016) (xy 0.2794 0.9906) (xy -0.2794 0.9906)
			)
			(stroke
				(width 0)
				(type default)
			)
			(fill no)
			(layer "F.CrtYd")
		)
		(fp_line
			(start -0.2794 0.9906)
			(end 0.2794 0.9906)
			(stroke
				(width 0.1)
				(type default)
			)
			(layer "F.Fab")
		)
		(fp_line
			(start 0.2794 0.9906)
			(end 0.2794 -0.1016)
			(stroke
				(width 0.1)
				(type default)
			)
			(layer "F.Fab")
		)
		(fp_line
			(start -0.2794 -0.1016)
			(end -0.2794 0.9906)
			(stroke
				(width 0.1)
				(type default)
			)
			(layer "F.Fab")
		)
		(fp_line
			(start 0.2794 -0.1016)
			(end -0.2794 -0.1016)
			(stroke
				(width 0.1)
				(type default)
			)
			(layer "F.Fab")
		)
		(pad "1" smd rect
			(at 0 0 270)
			(size 0.508 0.508)
			(layers "F.Cu" "F.Mask" "F.Paste")
			(net "PVCCIO_CPU0")
		)
		(pad "2" smd rect
			(at 0 0.889 270)
			(size 0.508 0.508)
			(layers "F.Cu" "F.Mask" "F.Paste")
			(net "SMB_CPU0_PE_HP_GTL_R_SDA")
		)
		(zone
			(layer "F.Cu")
			(hatch none 0.5)
			(connect_pads
				(clearance 0)
			)
			(min_thickness 0.25)
			(keepout
				(tracks not_allowed)
				(vias allowed)
				(pads allowed)
				(copperpour not_allowed)
				(footprints allowed)
			)
			(placement
				(enabled no)
				(sheetname "")
			)
			(fill
				(thermal_gap 0.5)
				(thermal_bridge_width 0.5)
				(island_removal_mode 0)
			)
			(polygon
				(pts
					(xy 421.6527 -105.283) (xy 421.6527 -104.775) (xy 422.0337 -104.775) (xy 422.0337 -105.283)
				)
			)
		)
		(zone
			(layer "F.Cu")
			(hatch none 0.5)
			(connect_pads
				(clearance 0)
			)
			(min_thickness 0.25)
			(keepout
				(tracks allowed)
				(vias not_allowed)
				(pads allowed)
				(copperpour not_allowed)
				(footprints allowed)
			)
			(placement
				(enabled no)
				(sheetname "")
			)
			(fill
				(thermal_gap 0.5)
				(thermal_bridge_width 0.5)
				(island_removal_mode 0)
			)
			(polygon
				(pts
					(xy 422.0337 -105.283) (xy 422.0337 -104.775) (xy 421.6527 -104.775) (xy 421.6527 -105.283)
				)
			)
		)
	)
	(footprint ""
		(layer "F.Cu")
		(at 401.8915 -48.006 90)
		(property "Reference" "C7F2"
			(at 0 0 90)
			(layer "F.SilkS")
			(hide yes)
			(effects
				(font
					(size 1.27 1.27)
				)
			)
		)
		(property "Value" ""
			(at 0 0 90)
			(layer "F.Fab")
			(effects
				(font
					(size 1.27 1.27)
				)
			)
		)
		(duplicate_pad_numbers_are_jumpers no)
		(fp_poly
			(pts
				(xy 0.3048 -0.1016) (xy 0.3048 0.9906) (xy -0.3048 0.9906) (xy -0.3048 -0.1016)
			)
			(stroke
				(width 0)
				(type default)
			)
			(fill no)
			(layer "F.CrtYd")
		)
		(fp_line
			(start 0.3048 -0.1016)
			(end -0.3048 -0.1016)
			(stroke
				(width 0.1)
				(type default)
			)
			(layer "F.Fab")
		)
		(fp_line
			(start -0.3048 -0.1016)
			(end -0.3048 0.9906)
			(stroke
				(width 0.1)
				(type default)
			)
			(layer "F.Fab")
		)
		(fp_line
			(start 0.3048 0.9906)
			(end 0.3048 -0.1016)
			(stroke
				(width 0.1)
				(type default)
			)
			(layer "F.Fab")
		)
		(fp_line
			(start -0.3048 0.9906)
			(end 0.3048 0.9906)
			(stroke
				(width 0.1)
				(type default)
			)
			(layer "F.Fab")
		)
		(pad "1" smd rect
			(at 0 0 90)
			(size 0.508 0.508)
			(layers "F.Cu" "F.Mask" "F.Paste")
			(net "P3V3_STBY")
		)
		(pad "2" smd rect
			(at 0 0.889 90)
			(size 0.508 0.508)
			(layers "F.Cu" "F.Mask" "F.Paste")
			(net "GND")
		)
		(zone
			(layer "F.Cu")
			(hatch none 0.5)
			(connect_pads
				(clearance 0)
			)
			(min_thickness 0.25)
			(keepout
				(tracks allowed)
				(vias not_allowed)
				(pads allowed)
				(copperpour not_allowed)
				(footprints allowed)
			)
			(placement
				(enabled no)
				(sheetname "")
			)
			(fill
				(thermal_gap 0.5)
				(thermal_bridge_width 0.5)
				(island_removal_mode 0)
			)
			(polygon
				(pts
					(xy 402.1455 -47.752) (xy 402.1455 -48.26) (xy 402.5265 -48.26) (xy 402.5265 -47.752)
				)
			)
		)
		(zone
			(layer "F.Cu")
			(hatch none 0.5)
			(connect_pads
				(clearance 0)
			)
			(min_thickness 0.25)
			(keepout
				(tracks not_allowed)
				(vias allowed)
				(pads allowed)
				(copperpour not_allowed)
				(footprints allowed)
			)
			(placement
				(enabled no)
				(sheetname "")
			)
			(fill
				(thermal_gap 0.5)
				(thermal_bridge_width 0.5)
				(island_removal_mode 0)
			)
			(polygon
				(pts
					(xy 402.5265 -47.752) (xy 402.5265 -48.26) (xy 402.1455 -48.26) (xy 402.1455 -47.752)
				)
			)
		)
	)
	(footprint ""
		(layer "F.Cu")
		(at 416.814 -82.55 90)
		(property "Reference" "R2P8"
			(at 0 0 90)
			(layer "F.SilkS")
			(hide yes)
			(effects
				(font
					(size 1.27 1.27)
				)
			)
		)
		(property "Value" ""
			(at 0 0 90)
			(layer "F.Fab")
			(effects
				(font
					(size 1.27 1.27)
				)
			)
		)
		(duplicate_pad_numbers_are_jumpers no)
		(fp_poly
			(pts
				(xy -0.2794 -0.1016) (xy 0.2794 -0.1016) (xy 0.2794 0.9906) (xy -0.2794 0.9906)
			)
			(stroke
				(width 0)
				(type default)
			)
			(fill no)
			(layer "F.CrtYd")
		)
		(fp_line
			(start 0.2794 -0.1016)
			(end -0.2794 -0.1016)
			(stroke
				(width 0.1)
				(type default)
			)
			(layer "F.Fab")
		)
		(fp_line
			(start -0.2794 -0.1016)
			(end -0.2794 0.9906)
			(stroke
				(width 0.1)
				(type default)
			)
			(layer "F.Fab")
		)
		(fp_line
			(start 0.2794 0.9906)
			(end 0.2794 -0.1016)
			(stroke
				(width 0.1)
				(type default)
			)
			(layer "F.Fab")
		)
		(fp_line
			(start -0.2794 0.9906)
			(end 0.2794 0.9906)
			(stroke
				(width 0.1)
				(type default)
			)
			(layer "F.Fab")
		)
		(pad "1" smd rect
			(at 0 0 90)
			(size 0.508 0.508)
			(layers "F.Cu" "F.Mask" "F.Paste")
			(net "P3V3_STBY")
		)
		(pad "2" smd rect
			(at 0 0.889 90)
			(size 0.508 0.508)
			(layers "F.Cu" "F.Mask" "F.Paste")
			(net "IRQ_SML1_PMBUS_ALERT_N")
		)
		(zone
			(layer "F.Cu")
			(hatch none 0.5)
			(connect_pads
				(clearance 0)
			)
			(min_thickness 0.25)
			(keepout
				(tracks allowed)
				(vias not_allowed)
				(pads allowed)
				(copperpour not_allowed)
				(footprints allowed)
			)
			(placement
				(enabled no)
				(sheetname "")
			)
			(fill
				(thermal_gap 0.5)
				(thermal_bridge_width 0.5)
				(island_removal_mode 0)
			)
			(polygon
				(pts
					(xy 417.068 -82.296) (xy 417.068 -82.804) (xy 417.449 -82.804) (xy 417.449 -82.296)
				)
			)
		)
		(zone
			(layer "F.Cu")
			(hatch none 0.5)
			(connect_pads
				(clearance 0)
			)
			(min_thickness 0.25)
			(keepout
				(tracks not_allowed)
				(vias allowed)
				(pads allowed)
				(copperpour not_allowed)
				(footprints allowed)
			)
			(placement
				(enabled no)
				(sheetname "")
			)
			(fill
				(thermal_gap 0.5)
				(thermal_bridge_width 0.5)
				(island_removal_mode 0)
			)
			(polygon
				(pts
					(xy 417.449 -82.296) (xy 417.449 -82.804) (xy 417.068 -82.804) (xy 417.068 -82.296)
				)
			)
		)
	)
	(footprint ""
		(layer "F.Cu")
		(at 104.35844 -73.279)
		(property "Reference" "C2D39"
			(at 0 0 0)
			(layer "F.SilkS")
			(hide yes)
			(effects
				(font
					(size 1.27 1.27)
				)
			)
		)
		(property "Value" ""
			(at 0 0 0)
			(layer "F.Fab")
			(effects
				(font
					(size 1.27 1.27)
				)
			)
		)
		(duplicate_pad_numbers_are_jumpers no)
		(fp_poly
			(pts
				(xy -0.4953 -0.2032) (xy 0.4953 -0.2032) (xy 0.4953 1.6002) (xy -0.4953 1.6002)
			)
			(stroke
				(width 0)
				(type default)
			)
			(fill no)
			(layer "F.CrtYd")
		)
		(fp_line
			(start -0.4953 -0.2032)
			(end 0.4953 -0.2032)
			(stroke
				(width 0.1)
				(type default)
			)
			(layer "F.Fab")
		)
		(fp_line
			(start -0.4953 1.6002)
			(end -0.4953 -0.2032)
			(stroke
				(width 0.1)
				(type default)
			)
			(layer "F.Fab")
		)
		(fp_line
			(start 0.4953 -0.2032)
			(end 0.4953 1.6002)
			(stroke
				(width 0.1)
				(type default)
			)
			(layer "F.Fab")
		)
		(fp_line
			(start 0.4953 1.6002)
			(end -0.4953 1.6002)
			(stroke
				(width 0.1)
				(type default)
			)
			(layer "F.Fab")
		)
		(pad "1" smd rect
			(at 0 0)
			(size 0.762 0.889)
			(layers "F.Cu" "F.Mask" "F.Paste")
			(net "PVCCMCP_CPU1")
		)
		(pad "2" smd rect
			(at 0 1.397)
			(size 0.762 0.889)
			(layers "F.Cu" "F.Mask" "F.Paste")
			(net "GND")
		)
		(zone
			(layer "F.Cu")
			(hatch none 0.5)
			(connect_pads
				(clearance 0)
			)
			(min_thickness 0.25)
			(keepout
				(tracks not_allowed)
				(vias allowed)
				(pads allowed)
				(copperpour not_allowed)
				(footprints allowed)
			)
			(placement
				(enabled no)
				(sheetname "")
			)
			(fill
				(thermal_gap 0.5)
				(thermal_bridge_width 0.5)
				(island_removal_mode 0)
			)
			(polygon
				(pts
					(xy 103.97744 -72.8345) (xy 104.73944 -72.8345) (xy 104.73944 -72.3265) (xy 103.97744 -72.3265)
				)
			)
		)
	)
	(footprint ""
		(layer "F.Cu")
		(at 392.023346 -64.7065)
		(property "Reference" "C8E16"
			(at 0 0 0)
			(layer "F.SilkS")
			(hide yes)
			(effects
				(font
					(size 1.27 1.27)
				)
			)
		)
		(property "Value" ""
			(at 0 0 0)
			(layer "F.Fab")
			(effects
				(font
					(size 1.27 1.27)
				)
			)
		)
		(duplicate_pad_numbers_are_jumpers no)
		(fp_poly
			(pts
				(xy 0.3048 -0.1016) (xy 0.3048 0.9906) (xy -0.3048 0.9906) (xy -0.3048 -0.1016)
			)
			(stroke
				(width 0)
				(type default)
			)
			(fill no)
			(layer "F.CrtYd")
		)
		(fp_line
			(start -0.3048 -0.1016)
			(end -0.3048 0.9906)
			(stroke
				(width 0.1)
				(type default)
			)
			(layer "F.Fab")
		)
		(fp_line
			(start -0.3048 0.9906)
			(end 0.3048 0.9906)
			(stroke
				(width 0.1)
				(type default)
			)
			(layer "F.Fab")
		)
		(fp_line
			(start 0.3048 -0.1016)
			(end -0.3048 -0.1016)
			(stroke
				(width 0.1)
				(type default)
			)
			(layer "F.Fab")
		)
		(fp_line
			(start 0.3048 0.9906)
			(end 0.3048 -0.1016)
			(stroke
				(width 0.1)
				(type default)
			)
			(layer "F.Fab")
		)
		(pad "1" smd rect
			(at 0 0)
			(size 0.508 0.508)
			(layers "F.Cu" "F.Mask" "F.Paste")
			(net "VR_P5V_STBY_COMP")
		)
		(pad "2" smd rect
			(at 0 0.889)
			(size 0.508 0.508)
			(layers "F.Cu" "F.Mask" "F.Paste")
			(net "AGND_P5V_STBY")
		)
		(zone
			(layer "F.Cu")
			(hatch none 0.5)
			(connect_pads
				(clearance 0)
			)
			(min_thickness 0.25)
			(keepout
				(tracks allowed)
				(vias not_allowed)
				(pads allowed)
				(copperpour not_allowed)
				(footprints allowed)
			)
			(placement
				(enabled no)
				(sheetname "")
			)
			(fill
				(thermal_gap 0.5)
				(thermal_bridge_width 0.5)
				(island_removal_mode 0)
			)
			(polygon
				(pts
					(xy 391.769346 -64.4525) (xy 392.277346 -64.4525) (xy 392.277346 -64.0715) (xy 391.769346 -64.0715)
				)
			)
		)
		(zone
			(layer "F.Cu")
			(hatch none 0.5)
			(connect_pads
				(clearance 0)
			)
			(min_thickness 0.25)
			(keepout
				(tracks not_allowed)
				(vias allowed)
				(pads allowed)
				(copperpour not_allowed)
				(footprints allowed)
			)
			(placement
				(enabled no)
				(sheetname "")
			)
			(fill
				(thermal_gap 0.5)
				(thermal_bridge_width 0.5)
				(island_removal_mode 0)
			)
			(polygon
				(pts
					(xy 391.769346 -64.0715) (xy 392.277346 -64.0715) (xy 392.277346 -64.4525) (xy 391.769346 -64.4525)
				)
			)
		)
	)
	(footprint ""
		(layer "F.Cu")
		(at 366.2172 -92.1766 180)
		(property "Reference" "C7D1"
			(at 0 0 180)
			(layer "F.SilkS")
			(hide yes)
			(effects
				(font
					(size 1.27 1.27)
				)
			)
		)
		(property "Value" ""
			(at 0 0 180)
			(layer "F.Fab")
			(effects
				(font
					(size 1.27 1.27)
				)
			)
		)
		(duplicate_pad_numbers_are_jumpers no)
		(fp_poly
			(pts
				(xy 0.3048 -0.1016) (xy 0.3048 0.9906) (xy -0.3048 0.9906) (xy -0.3048 -0.1016)
			)
			(stroke
				(width 0)
				(type default)
			)
			(fill no)
			(layer "F.CrtYd")
		)
		(fp_line
			(start 0.3048 0.9906)
			(end 0.3048 -0.1016)
			(stroke
				(width 0.1)
				(type default)
			)
			(layer "F.Fab")
		)
		(fp_line
			(start 0.3048 -0.1016)
			(end -0.3048 -0.1016)
			(stroke
				(width 0.1)
				(type default)
			)
			(layer "F.Fab")
		)
		(fp_line
			(start -0.3048 0.9906)
			(end 0.3048 0.9906)
			(stroke
				(width 0.1)
				(type default)
			)
			(layer "F.Fab")
		)
		(fp_line
			(start -0.3048 -0.1016)
			(end -0.3048 0.9906)
			(stroke
				(width 0.1)
				(type default)
			)
			(layer "F.Fab")
		)
		(pad "1" smd rect
			(at 0 0 180)
			(size 0.508 0.508)
			(layers "F.Cu" "F.Mask" "F.Paste")
			(net "P3V3_STBY")
		)
		(pad "2" smd rect
			(at 0 0.889 180)
			(size 0.508 0.508)
			(layers "F.Cu" "F.Mask" "F.Paste")
			(net "GND")
		)
		(zone
			(layer "F.Cu")
			(hatch none 0.5)
			(connect_pads
				(clearance 0)
			)
			(min_thickness 0.25)
			(keepout
				(tracks not_allowed)
				(vias allowed)
				(pads allowed)
				(copperpour not_allowed)
				(footprints allowed)
			)
			(placement
				(enabled no)
				(sheetname "")
			)
			(fill
				(thermal_gap 0.5)
				(thermal_bridge_width 0.5)
				(island_removal_mode 0)
			)
			(polygon
				(pts
					(xy 366.4712 -92.8116) (xy 365.9632 -92.8116) (xy 365.9632 -92.4306) (xy 366.4712 -92.4306)
				)
			)
		)
		(zone
			(layer "F.Cu")
			(hatch none 0.5)
			(connect_pads
				(clearance 0)
			)
			(min_thickness 0.25)
			(keepout
				(tracks allowed)
				(vias not_allowed)
				(pads allowed)
				(copperpour not_allowed)
				(footprints allowed)
			)
			(placement
				(enabled no)
				(sheetname "")
			)
			(fill
				(thermal_gap 0.5)
				(thermal_bridge_width 0.5)
				(island_removal_mode 0)
			)
			(polygon
				(pts
					(xy 366.4712 -92.4306) (xy 365.9632 -92.4306) (xy 365.9632 -92.8116) (xy 366.4712 -92.8116)
				)
			)
		)
	)
	(footprint ""
		(layer "F.Cu")
		(at 435.404006 -41.663874 180)
		(property "Reference" "R25W4"
			(at 0 0 180)
			(layer "F.SilkS")
			(hide yes)
			(effects
				(font
					(size 1.27 1.27)
				)
			)
		)
		(property "Value" "*"
			(at 0.064008 -4.108196 180)
			(unlocked yes)
			(layer "F.Fab")
			(hide yes)
			(effects
				(font
					(size 1.27 1.016)
					(thickness 0.1524)
				)
			)
		)
		(property "Device Type" "120R2F-GP_RCL_GP-120R2F-GP,64.A"
			(at 0.064008 -5.632196 180)
			(unlocked yes)
			(layer "F.Fab")
			(hide yes)
			(effects
				(font
					(size 1.27 1.016)
					(thickness 0.1524)
				)
			)
		)
		(duplicate_pad_numbers_are_jumpers no)
		(fp_line
			(start 0.508 -0.9398)
			(end -0.508 -0.9398)
			(stroke
				(width 0.1524)
				(type default)
			)
			(layer "F.SilkS")
		)
		(fp_line
			(start -0.508 -0.9398)
			(end -0.508 0.9398)
			(stroke
				(width 0.1524)
				(type default)
			)
			(layer "F.SilkS")
		)
		(fp_rect
			(start -0.508 0.9398)
			(end 0.508 -0.9398)
			(stroke
				(width 0)
				(type default)
			)
			(fill no)
			(layer "F.CrtYd")
		)
		(fp_rect
			(start -0.508 0.9398)
			(end 0.508 -0.9398)
			(stroke
				(width 0)
				(type default)
			)
			(fill no)
			(layer "F.Fab")
		)
		(pad "1" smd custom
			(at 0 -0.4445 180)
			(size 0.1397 0.1397)
			(layers "F.Cu" "F.Mask" "F.Paste")
			(net "GND")
			(options
				(clearance outline)
				(anchor circle)
			)
			(primitives
				(gr_poly
					(pts
						(arc
							(start -0.1778 -0.2794)
							(mid -0.249642 -0.249642)
							(end -0.2794 -0.1778)
						)
						(arc
							(start -0.2794 0.1778)
							(mid -0.249642 0.249642)
							(end -0.1778 0.2794)
						)
						(arc
							(start 0.1778 0.2794)
							(mid 0.249642 0.249642)
							(end 0.2794 0.1778)
						)
						(arc
							(start 0.2794 -0.1778)
							(mid 0.249642 -0.249642)
							(end 0.1778 -0.2794)
						)
					)
					(width 0)
					(fill yes)
				)
			)
		)
		(pad "2" smd custom
			(at 0 0.4445 180)
			(size 0.1397 0.1397)
			(layers "F.Cu" "F.Mask" "F.Paste")
			(net "BMC_M_MALERT_N")
			(options
				(clearance outline)
				(anchor circle)
			)
			(primitives
				(gr_poly
					(pts
						(arc
							(start -0.1778 -0.2794)
							(mid -0.249642 -0.249642)
							(end -0.2794 -0.1778)
						)
						(arc
							(start -0.2794 0.1778)
							(mid -0.249642 0.249642)
							(end -0.1778 0.2794)
						)
						(arc
							(start 0.1778 0.2794)
							(mid 0.249642 0.249642)
							(end 0.2794 0.1778)
						)
						(arc
							(start 0.2794 -0.1778)
							(mid 0.249642 -0.249642)
							(end 0.1778 -0.2794)
						)
					)
					(width 0)
					(fill yes)
				)
			)
		)
	)
)
